(kicad_pcb
	(version 20260206)
	(generator "pcbnew")
	(generator_version "10.0")
	(general
		(thickness 1.6)
		(legacy_teardrops no)
	)
	(paper "A4")
	(title_block
		(title "panther-plus-userver — 13130-1b_20150205.brd")
		(comment 1 "Honey Badger (Wiwynn) / footprints 663-671 of 1509")
	)
	(layers
		(0 "F.Cu" signal "TOP")
		(4 "In1.Cu" signal "L2")
		(6 "In2.Cu" signal "L3")
		(8 "In3.Cu" signal "L4")
		(10 "In4.Cu" signal "L5")
		(12 "In5.Cu" signal "L6")
		(14 "In6.Cu" signal "L7")
		(16 "In7.Cu" signal "L8")
		(18 "In8.Cu" signal "L9")
		(20 "In9.Cu" signal "L10")
		(22 "In10.Cu" signal "L11")
		(2 "B.Cu" signal "BOTTOM")
		(9 "F.Adhes" user "F.Adhesive")
		(11 "B.Adhes" user "B.Adhesive")
		(13 "F.Paste" user "Package Geometry/Pastemask Top")
		(15 "B.Paste" user "Package Geometry/Pastemask Bottom")
		(5 "F.SilkS" user "Ref Des/Silkscreen Top")
		(7 "B.SilkS" user "Ref Des/Silkscreen Bottom")
		(1 "F.Mask" user "Board Geometry/Soldermask Top")
		(3 "B.Mask" user "Board Geometry/Soldermask Bottom")
		(17 "Dwgs.User" user "User.Drawings")
		(19 "Cmts.User" user "User.Comments")
		(21 "Eco1.User" user "User.Eco1")
		(23 "Eco2.User" user "User.Eco2")
		(25 "Edge.Cuts" user "Board Geometry/Outline")
		(27 "Margin" user)
		(31 "F.CrtYd" user "Package Geometry/Place Bound Top")
		(29 "B.CrtYd" user "Package Geometry/Place Bound Bottom")
		(35 "F.Fab" user "Ref Des/Assembly Top")
		(33 "B.Fab" user "Ref Des/Assembly Bottom")
	)
	(footprint ""
		(layer "F.Cu")
		(at 56.007 -36.068 -90)
		(property "Reference" "R106"
			(at 0 0 270)
			(layer "F.SilkS")
			(hide yes)
			(effects
				(font
					(size 1.27 1.27)
				)
			)
		)
		(property "Value" "33R2F-3-GP"
			(at 0.064008 -3.993896 270)
			(unlocked yes)
			(layer "F.Fab")
			(hide yes)
			(effects
				(font
					(size 1.016 1.016)
					(thickness 0.1524)
				)
			)
		)
		(property "Device Type" "R402H16"
			(at 0.064008 -5.517896 270)
			(unlocked yes)
			(layer "F.Fab")
			(hide yes)
			(effects
				(font
					(size 1.016 1.016)
					(thickness 0.1524)
				)
			)
		)
		(duplicate_pad_numbers_are_jumpers no)
		(fp_rect
			(start -0.381 0.8382)
			(end 0.381 -0.8382)
			(stroke
				(width 0)
				(type default)
			)
			(fill no)
			(layer "F.CrtYd")
		)
		(fp_rect
			(start -0.381 0.8382)
			(end 0.381 -0.8382)
			(stroke
				(width 0)
				(type default)
			)
			(fill no)
			(layer "F.Fab")
		)
		(pad "1" smd custom
			(at 0 -0.4318 270)
			(size 0.127 0.127)
			(layers "F.Cu" "F.Mask" "F.Paste")
			(net "SPI_CPU_MISO")
			(options
				(clearance outline)
				(anchor circle)
			)
			(primitives
				(gr_poly
					(pts
						(arc
							(start -0.2032 -0.2794)
							(mid -0.239121 -0.264521)
							(end -0.254 -0.2286)
						)
						(arc
							(start -0.254 0.2286)
							(mid -0.239121 0.264521)
							(end -0.2032 0.2794)
						)
						(arc
							(start 0.2032 0.2794)
							(mid 0.239121 0.264521)
							(end 0.254 0.2286)
						)
						(arc
							(start 0.254 -0.2286)
							(mid 0.239121 -0.264521)
							(end 0.2032 -0.2794)
						)
					)
					(width 0)
					(fill yes)
				)
			)
		)
		(pad "2" smd custom
			(at 0 0.4318 270)
			(size 0.127 0.127)
			(layers "F.Cu" "F.Mask" "F.Paste")
			(net "SPI_MISO_R_1")
			(options
				(clearance outline)
				(anchor circle)
			)
			(primitives
				(gr_poly
					(pts
						(arc
							(start -0.2032 -0.2794)
							(mid -0.239121 -0.264521)
							(end -0.254 -0.2286)
						)
						(arc
							(start -0.254 0.2286)
							(mid -0.239121 0.264521)
							(end -0.2032 0.2794)
						)
						(arc
							(start 0.2032 0.2794)
							(mid 0.239121 0.264521)
							(end 0.254 0.2286)
						)
						(arc
							(start 0.254 -0.2286)
							(mid 0.239121 -0.264521)
							(end 0.2032 -0.2794)
						)
					)
					(width 0)
					(fill yes)
				)
			)
		)
	)
	(footprint ""
		(layer "F.Cu")
		(at 21.9456 -65.1764)
		(property "Reference" "PR28"
			(at 0 0 0)
			(layer "F.SilkS")
			(hide yes)
			(effects
				(font
					(size 1.27 1.27)
				)
			)
		)
		(property "Value" "1K3R2F-1-GP"
			(at 1.7907 -1.1176 0)
			(unlocked yes)
			(layer "F.Fab")
			(hide yes)
			(effects
				(font
					(size 1.016 1.016)
					(thickness 0.1524)
				)
			)
		)
		(property "Device Type" "R402H16"
			(at 1.7907 -2.6416 0)
			(unlocked yes)
			(layer "F.Fab")
			(hide yes)
			(effects
				(font
					(size 1.016 1.016)
					(thickness 0.1524)
				)
			)
		)
		(duplicate_pad_numbers_are_jumpers no)
		(fp_rect
			(start -0.381 0.8382)
			(end 0.381 -0.8382)
			(stroke
				(width 0)
				(type default)
			)
			(fill no)
			(layer "F.CrtYd")
		)
		(fp_rect
			(start -0.381 0.8382)
			(end 0.381 -0.8382)
			(stroke
				(width 0)
				(type default)
			)
			(fill no)
			(layer "F.Fab")
		)
		(pad "1" smd custom
			(at 0 -0.4318)
			(size 0.127 0.127)
			(layers "F.Cu" "F.Mask" "F.Paste")
			(net "VR_PVNN_ISUMN")
			(options
				(clearance outline)
				(anchor circle)
			)
			(primitives
				(gr_poly
					(pts
						(arc
							(start -0.2032 -0.2794)
							(mid -0.239121 -0.264521)
							(end -0.254 -0.2286)
						)
						(arc
							(start -0.254 0.2286)
							(mid -0.239121 0.264521)
							(end -0.2032 0.2794)
						)
						(arc
							(start 0.2032 0.2794)
							(mid 0.239121 0.264521)
							(end 0.254 0.2286)
						)
						(arc
							(start 0.254 -0.2286)
							(mid 0.239121 -0.264521)
							(end 0.2032 -0.2794)
						)
					)
					(width 0)
					(fill yes)
				)
			)
		)
		(pad "2" smd custom
			(at 0 0.4318)
			(size 0.127 0.127)
			(layers "F.Cu" "F.Mask" "F.Paste")
			(net "VR_PVNN_ISUMN_R")
			(options
				(clearance outline)
				(anchor circle)
			)
			(primitives
				(gr_poly
					(pts
						(arc
							(start -0.2032 -0.2794)
							(mid -0.239121 -0.264521)
							(end -0.254 -0.2286)
						)
						(arc
							(start -0.254 0.2286)
							(mid -0.239121 0.264521)
							(end -0.2032 0.2794)
						)
						(arc
							(start 0.2032 0.2794)
							(mid 0.239121 0.264521)
							(end 0.254 0.2286)
						)
						(arc
							(start 0.254 -0.2286)
							(mid 0.239121 -0.264521)
							(end 0.2032 -0.2794)
						)
					)
					(width 0)
					(fill yes)
				)
			)
		)
	)
	(footprint ""
		(layer "F.Cu")
		(at 154.94 -23.622 90)
		(property "Reference" "C73"
			(at 0 0 90)
			(layer "F.SilkS")
			(hide yes)
			(effects
				(font
					(size 1.27 1.27)
				)
			)
		)
		(property "Value" "SCD1U10V2KX-5GP"
			(at 1.1811 -2.7051 90)
			(unlocked yes)
			(layer "F.Fab")
			(hide yes)
			(effects
				(font
					(size 1.016 1.016)
					(thickness 0.1524)
				)
			)
		)
		(property "Device Type" "C402H22"
			(at 1.1811 -4.2291 90)
			(unlocked yes)
			(layer "F.Fab")
			(hide yes)
			(effects
				(font
					(size 1.016 1.016)
					(thickness 0.1524)
				)
			)
		)
		(duplicate_pad_numbers_are_jumpers no)
		(fp_rect
			(start -0.381 0.7366)
			(end 0.381 -0.7366)
			(stroke
				(width 0)
				(type default)
			)
			(fill no)
			(layer "F.CrtYd")
		)
		(fp_rect
			(start -0.381 0.7366)
			(end 0.381 -0.7366)
			(stroke
				(width 0)
				(type default)
			)
			(fill no)
			(layer "F.Fab")
		)
		(pad "1" smd custom
			(at 0 -0.4572 90)
			(size 0.1143 0.1143)
			(layers "F.Cu" "F.Mask" "F.Paste")
			(net "P1V2_FPGA_A")
			(options
				(clearance outline)
				(anchor circle)
			)
			(primitives
				(gr_poly
					(pts
						(arc
							(start -0.254 -0.1778)
							(mid -0.239121 -0.213721)
							(end -0.2032 -0.2286)
						)
						(arc
							(start 0.2032 -0.2286)
							(mid 0.239121 -0.213721)
							(end 0.254 -0.1778)
						)
						(arc
							(start 0.254 0.1778)
							(mid 0.239121 0.213721)
							(end 0.2032 0.2286)
						)
						(arc
							(start -0.2032 0.2286)
							(mid -0.239121 0.213721)
							(end -0.254 0.1778)
						)
					)
					(width 0)
					(fill yes)
				)
			)
		)
		(pad "2" smd custom
			(at 0 0.4572 90)
			(size 0.1143 0.1143)
			(layers "F.Cu" "F.Mask" "F.Paste")
			(net "GND")
			(options
				(clearance outline)
				(anchor circle)
			)
			(primitives
				(gr_poly
					(pts
						(arc
							(start -0.254 -0.1778)
							(mid -0.239121 -0.213721)
							(end -0.2032 -0.2286)
						)
						(arc
							(start 0.2032 -0.2286)
							(mid 0.239121 -0.213721)
							(end 0.254 -0.1778)
						)
						(arc
							(start 0.254 0.1778)
							(mid 0.239121 0.213721)
							(end 0.2032 0.2286)
						)
						(arc
							(start -0.2032 0.2286)
							(mid -0.239121 0.213721)
							(end -0.254 0.1778)
						)
					)
					(width 0)
					(fill yes)
				)
			)
		)
	)
	(footprint ""
		(layer "F.Cu")
		(at 161.798 -42.545 90)
		(property "Reference" "LED3"
			(at 0 0 90)
			(layer "F.SilkS")
			(hide yes)
			(effects
				(font
					(size 1.27 1.27)
				)
			)
		)
		(property "Value" "LED-YG-51-GP"
			(at -2.6924 -1.4224 90)
			(unlocked yes)
			(layer "F.Fab")
			(hide yes)
			(effects
				(font
					(size 1.016 1.016)
					(thickness 0.1524)
				)
			)
		)
		(property "Device Type" "LED1608AKH40"
			(at -2.6924 -2.9464 90)
			(unlocked yes)
			(layer "F.Fab")
			(hide yes)
			(effects
				(font
					(size 1.016 1.016)
					(thickness 0.1524)
				)
			)
		)
		(duplicate_pad_numbers_are_jumpers no)
		(fp_line
			(start -0.5334 1.3081)
			(end 0.5334 1.3081)
			(stroke
				(width 0.254)
				(type default)
			)
			(layer "F.SilkS")
		)
		(fp_rect
			(start -0.6604 1.1811)
			(end 0.6604 -1.1811)
			(stroke
				(width 0)
				(type default)
			)
			(fill no)
			(layer "F.CrtYd")
		)
		(fp_rect
			(start -0.6604 1.1811)
			(end 0.6604 -1.1811)
			(stroke
				(width 0)
				(type default)
			)
			(fill no)
			(layer "F.Fab")
		)
		(pad "A" smd rect
			(at 0 -0.652526 90)
			(size 1.0668 0.8128)
			(layers "F.Cu" "F.Mask" "F.Paste")
			(net "C_LED_NSTATUS#")
		)
		(pad "K" smd rect
			(at 0 0.652526 90)
			(size 1.0668 0.8128)
			(layers "F.Cu" "F.Mask" "F.Paste")
			(net "C_NSTATUS#")
		)
	)
	(footprint ""
		(layer "F.Cu")
		(at 4.699 -46.228)
		(property "Reference" "R8"
			(at 0 0 0)
			(layer "F.SilkS")
			(hide yes)
			(effects
				(font
					(size 1.27 1.27)
				)
			)
		)
		(property "Value" "0R2J-2-GP"
			(at 0.064008 -3.993896 0)
			(unlocked yes)
			(layer "F.Fab")
			(hide yes)
			(effects
				(font
					(size 1.016 1.016)
					(thickness 0.1524)
				)
			)
		)
		(property "Device Type" "R402H16"
			(at 0.064008 -5.517896 0)
			(unlocked yes)
			(layer "F.Fab")
			(hide yes)
			(effects
				(font
					(size 1.016 1.016)
					(thickness 0.1524)
				)
			)
		)
		(duplicate_pad_numbers_are_jumpers no)
		(fp_rect
			(start -0.381 0.8382)
			(end 0.381 -0.8382)
			(stroke
				(width 0)
				(type default)
			)
			(fill no)
			(layer "F.CrtYd")
		)
		(fp_rect
			(start -0.381 0.8382)
			(end 0.381 -0.8382)
			(stroke
				(width 0)
				(type default)
			)
			(fill no)
			(layer "F.Fab")
		)
		(pad "1" smd custom
			(at 0 -0.4318)
			(size 0.127 0.127)
			(layers "F.Cu" "F.Mask" "F.Paste")
			(net "SMB_HOST_LV_CLK")
			(options
				(clearance outline)
				(anchor circle)
			)
			(primitives
				(gr_poly
					(pts
						(arc
							(start -0.2032 -0.2794)
							(mid -0.239121 -0.264521)
							(end -0.254 -0.2286)
						)
						(arc
							(start -0.254 0.2286)
							(mid -0.239121 0.264521)
							(end -0.2032 0.2794)
						)
						(arc
							(start 0.2032 0.2794)
							(mid 0.239121 0.264521)
							(end 0.254 0.2286)
						)
						(arc
							(start 0.254 -0.2286)
							(mid 0.239121 -0.264521)
							(end 0.2032 -0.2794)
						)
					)
					(width 0)
					(fill yes)
				)
			)
		)
		(pad "2" smd custom
			(at 0 0.4318)
			(size 0.127 0.127)
			(layers "F.Cu" "F.Mask" "F.Paste")
			(net "TEMP_1_CLK")
			(options
				(clearance outline)
				(anchor circle)
			)
			(primitives
				(gr_poly
					(pts
						(arc
							(start -0.2032 -0.2794)
							(mid -0.239121 -0.264521)
							(end -0.254 -0.2286)
						)
						(arc
							(start -0.254 0.2286)
							(mid -0.239121 0.264521)
							(end -0.2032 0.2794)
						)
						(arc
							(start 0.2032 0.2794)
							(mid 0.239121 0.264521)
							(end 0.254 0.2286)
						)
						(arc
							(start 0.254 -0.2286)
							(mid 0.239121 -0.264521)
							(end 0.2032 -0.2794)
						)
					)
					(width 0)
					(fill yes)
				)
			)
		)
	)
	(footprint ""
		(layer "F.Cu")
		(at 161.036 -33.274)
		(property "Reference" "R163"
			(at 0 0 0)
			(layer "F.SilkS")
			(hide yes)
			(effects
				(font
					(size 1.27 1.27)
				)
			)
		)
		(property "Value" "1KR2F-3-GP"
			(at 0.064008 -3.993896 0)
			(unlocked yes)
			(layer "F.Fab")
			(hide yes)
			(effects
				(font
					(size 1.016 1.016)
					(thickness 0.1524)
				)
			)
		)
		(property "Device Type" "R402H16"
			(at 0.064008 -5.517896 0)
			(unlocked yes)
			(layer "F.Fab")
			(hide yes)
			(effects
				(font
					(size 1.016 1.016)
					(thickness 0.1524)
				)
			)
		)
		(duplicate_pad_numbers_are_jumpers no)
		(fp_rect
			(start -0.381 0.8382)
			(end 0.381 -0.8382)
			(stroke
				(width 0)
				(type default)
			)
			(fill no)
			(layer "F.CrtYd")
		)
		(fp_rect
			(start -0.381 0.8382)
			(end 0.381 -0.8382)
			(stroke
				(width 0)
				(type default)
			)
			(fill no)
			(layer "F.Fab")
		)
		(pad "1" smd custom
			(at 0 -0.4318)
			(size 0.127 0.127)
			(layers "F.Cu" "F.Mask" "F.Paste")
			(net "P3V3_STBY")
			(options
				(clearance outline)
				(anchor circle)
			)
			(primitives
				(gr_poly
					(pts
						(arc
							(start -0.2032 -0.2794)
							(mid -0.239121 -0.264521)
							(end -0.254 -0.2286)
						)
						(arc
							(start -0.254 0.2286)
							(mid -0.239121 0.264521)
							(end -0.2032 0.2794)
						)
						(arc
							(start 0.2032 0.2794)
							(mid 0.239121 0.264521)
							(end 0.254 0.2286)
						)
						(arc
							(start 0.254 -0.2286)
							(mid 0.239121 -0.264521)
							(end 0.2032 -0.2794)
						)
					)
					(width 0)
					(fill yes)
				)
			)
		)
		(pad "2" smd custom
			(at 0 0.4318)
			(size 0.127 0.127)
			(layers "F.Cu" "F.Mask" "F.Paste")
			(net "DISABLE_H")
			(options
				(clearance outline)
				(anchor circle)
			)
			(primitives
				(gr_poly
					(pts
						(arc
							(start -0.2032 -0.2794)
							(mid -0.239121 -0.264521)
							(end -0.254 -0.2286)
						)
						(arc
							(start -0.254 0.2286)
							(mid -0.239121 0.264521)
							(end -0.2032 0.2794)
						)
						(arc
							(start 0.2032 0.2794)
							(mid 0.239121 0.264521)
							(end 0.254 0.2286)
						)
						(arc
							(start 0.254 -0.2286)
							(mid 0.239121 -0.264521)
							(end 0.2032 -0.2794)
						)
					)
					(width 0)
					(fill yes)
				)
			)
		)
	)
	(footprint ""
		(layer "F.Cu")
		(at 189.103 -60.325)
		(property "Reference" "C2"
			(at 0 0 0)
			(layer "F.SilkS")
			(hide yes)
			(effects
				(font
					(size 1.27 1.27)
				)
			)
		)
		(property "Value" "SCD1U16V2KX-3GP"
			(at 1.1811 -2.7051 0)
			(unlocked yes)
			(layer "F.Fab")
			(hide yes)
			(effects
				(font
					(size 1.016 1.016)
					(thickness 0.1524)
				)
			)
		)
		(property "Device Type" "C402H22"
			(at 1.1811 -4.2291 0)
			(unlocked yes)
			(layer "F.Fab")
			(hide yes)
			(effects
				(font
					(size 1.016 1.016)
					(thickness 0.1524)
				)
			)
		)
		(duplicate_pad_numbers_are_jumpers no)
		(fp_rect
			(start -0.381 0.7366)
			(end 0.381 -0.7366)
			(stroke
				(width 0)
				(type default)
			)
			(fill no)
			(layer "F.CrtYd")
		)
		(fp_rect
			(start -0.381 0.7366)
			(end 0.381 -0.7366)
			(stroke
				(width 0)
				(type default)
			)
			(fill no)
			(layer "F.Fab")
		)
		(pad "1" smd custom
			(at 0 -0.4572)
			(size 0.1143 0.1143)
			(layers "F.Cu" "F.Mask" "F.Paste")
			(net "DDR3_M_A_VREF_DQ1")
			(options
				(clearance outline)
				(anchor circle)
			)
			(primitives
				(gr_poly
					(pts
						(arc
							(start -0.254 -0.1778)
							(mid -0.239121 -0.213721)
							(end -0.2032 -0.2286)
						)
						(arc
							(start 0.2032 -0.2286)
							(mid 0.239121 -0.213721)
							(end 0.254 -0.1778)
						)
						(arc
							(start 0.254 0.1778)
							(mid 0.239121 0.213721)
							(end 0.2032 0.2286)
						)
						(arc
							(start -0.2032 0.2286)
							(mid -0.239121 0.213721)
							(end -0.254 0.1778)
						)
					)
					(width 0)
					(fill yes)
				)
			)
		)
		(pad "2" smd custom
			(at 0 0.4572)
			(size 0.1143 0.1143)
			(layers "F.Cu" "F.Mask" "F.Paste")
			(net "GND")
			(options
				(clearance outline)
				(anchor circle)
			)
			(primitives
				(gr_poly
					(pts
						(arc
							(start -0.254 -0.1778)
							(mid -0.239121 -0.213721)
							(end -0.2032 -0.2286)
						)
						(arc
							(start 0.2032 -0.2286)
							(mid 0.239121 -0.213721)
							(end 0.254 -0.1778)
						)
						(arc
							(start 0.254 0.1778)
							(mid 0.239121 0.213721)
							(end 0.2032 0.2286)
						)
						(arc
							(start -0.2032 0.2286)
							(mid -0.239121 0.213721)
							(end -0.254 0.1778)
						)
					)
					(width 0)
					(fill yes)
				)
			)
		)
	)
	(footprint ""
		(layer "F.Cu")
		(at 58.039 -63.754 180)
		(property "Reference" "PC37"
			(at 0 0 180)
			(layer "F.SilkS")
			(hide yes)
			(effects
				(font
					(size 1.27 1.27)
				)
			)
		)
		(property "Value" "SC47U6D3V5MX-1-GP"
			(at -0.0762 -6.1214 180)
			(unlocked yes)
			(layer "F.Fab")
			(hide yes)
			(effects
				(font
					(size 1.016 1.016)
					(thickness 0.1524)
				)
			)
		)
		(property "Device Type" "C805H54"
			(at -0.0762 -8.1534 180)
			(unlocked yes)
			(layer "F.Fab")
			(hide yes)
			(effects
				(font
					(size 1.016 1.016)
					(thickness 0.1524)
				)
			)
		)
		(duplicate_pad_numbers_are_jumpers no)
		(fp_line
			(start 0.6096 0)
			(end -0.6096 0)
			(stroke
				(width 0.3048)
				(type default)
			)
			(layer "F.SilkS")
		)
		(fp_poly
			(pts
				(xy -0.9017 1.4351) (xy 0.9017 1.4351) (xy 0.9017 -1.4351) (xy -0.9017 -1.4351)
			)
			(stroke
				(width 0)
				(type default)
			)
			(fill no)
			(layer "F.CrtYd")
		)
		(fp_poly
			(pts
				(xy 0.9017 1.4351) (xy 0.9017 -1.4351) (xy -0.9017 -1.4351) (xy -0.9017 1.4351)
			)
			(stroke
				(width 0)
				(type default)
			)
			(fill no)
			(layer "F.Fab")
		)
		(pad "1" smd rect
			(at 0 -0.8382 180)
			(size 1.5494 0.9398)
			(layers "F.Cu" "F.Mask" "F.Paste")
			(net "PVCCP")
		)
		(pad "2" smd rect
			(at 0 0.8382 180)
			(size 1.5494 0.9398)
			(layers "F.Cu" "F.Mask" "F.Paste")
			(net "GND")
		)
	)
	(footprint ""
		(layer "F.Cu")
		(at 198.755 -9.272778)
		(property "Reference" "R392"
			(at 0 0 0)
			(layer "F.SilkS")
			(hide yes)
			(effects
				(font
					(size 1.27 1.27)
				)
			)
		)
		(property "Value" "0R2J-2-GP"
			(at 0.064008 -3.993896 0)
			(unlocked yes)
			(layer "F.Fab")
			(hide yes)
			(effects
				(font
					(size 1.016 1.016)
					(thickness 0.1524)
				)
			)
		)
		(property "Device Type" "R402H16"
			(at 0.064008 -5.517896 0)
			(unlocked yes)
			(layer "F.Fab")
			(hide yes)
			(effects
				(font
					(size 1.016 1.016)
					(thickness 0.1524)
				)
			)
		)
		(duplicate_pad_numbers_are_jumpers no)
		(fp_rect
			(start -0.381 0.8382)
			(end 0.381 -0.8382)
			(stroke
				(width 0)
				(type default)
			)
			(fill no)
			(layer "F.CrtYd")
		)
		(fp_rect
			(start -0.381 0.8382)
			(end 0.381 -0.8382)
			(stroke
				(width 0)
				(type default)
			)
			(fill no)
			(layer "F.Fab")
		)
		(pad "1" smd custom
			(at 0 -0.4318)
			(size 0.127 0.127)
			(layers "F.Cu" "F.Mask" "F.Paste")
			(net "SMB_M_B1_R_CLK")
			(options
				(clearance outline)
				(anchor circle)
			)
			(primitives
				(gr_poly
					(pts
						(arc
							(start -0.2032 -0.2794)
							(mid -0.239121 -0.264521)
							(end -0.254 -0.2286)
						)
						(arc
							(start -0.254 0.2286)
							(mid -0.239121 0.264521)
							(end -0.2032 0.2794)
						)
						(arc
							(start 0.2032 0.2794)
							(mid 0.239121 0.264521)
							(end 0.254 0.2286)
						)
						(arc
							(start 0.254 -0.2286)
							(mid 0.239121 -0.264521)
							(end 0.2032 -0.2794)
						)
					)
					(width 0)
					(fill yes)
				)
			)
		)
		(pad "2" smd custom
			(at 0 0.4318)
			(size 0.127 0.127)
			(layers "F.Cu" "F.Mask" "F.Paste")
			(net "SMB_HOST_LV_CLK")
			(options
				(clearance outline)
				(anchor circle)
			)
			(primitives
				(gr_poly
					(pts
						(arc
							(start -0.2032 -0.2794)
							(mid -0.239121 -0.264521)
							(end -0.254 -0.2286)
						)
						(arc
							(start -0.254 0.2286)
							(mid -0.239121 0.264521)
							(end -0.2032 0.2794)
						)
						(arc
							(start 0.2032 0.2794)
							(mid 0.239121 0.264521)
							(end 0.254 0.2286)
						)
						(arc
							(start 0.254 -0.2286)
							(mid 0.239121 -0.264521)
							(end 0.2032 -0.2794)
						)
					)
					(width 0)
					(fill yes)
				)
			)
		)
	)
)
